# T6G (Grand Teton) — schematic netlist excerpt (pin names and nets, part order shuffled) for the footprints in the layout excerpt that follows; sources: Cadence DE-HDL packaged netlist, KiCad conversion of 04192023_DAF0TMB3IC0_F0TG_MB_C_brd_V02_OCP.brd

PR6627  Q_RES  2.2 5% CHIP  pkg 0402LF  page 365 : A = P0V9_RETIMER_CPU1_PVCC ; B = P0V9_RETIMER_CPU1_VCC2
PC1600  Q_CAP  22UF 10V 20% X6S  pkg C0805  page 190 : A = P3V3_AUX ; B = GND
R8310  Q_RES  33 5% CHIP  pkg 0402LF  page 193 : A = PVDDCR_CPU0_P0_PMALERT ; B = PVDDCR_CPU0_P0_PMALERT_R

(kicad_pcb
	(version 20260206)
	(generator "pcbnew")
	(generator_version "10.0")
	(general
		(thickness 1.6)
		(legacy_teardrops no)
	)
	(paper "A4")
	(title_block
		(title "04192023_DAF0TMB3IC0_F0TG_MB_C_brd_V02_OCP.brd")
		(comment 1 "Grand Teton / footprints 6606-6608 of 8354")
	)
	(layers
		(0 "F.Cu" signal "TOP")
		(4 "In1.Cu" signal "GND")
		(6 "In2.Cu" signal "IN1")
		(8 "In3.Cu" signal "GND1")
		(10 "In4.Cu" signal "IN2")
		(12 "In5.Cu" signal "GND2")
		(14 "In6.Cu" signal "IN3")
		(16 "In7.Cu" signal "GND3")
		(18 "In8.Cu" signal "VCC")
		(20 "In9.Cu" signal "VCC1")
		(22 "In10.Cu" signal "GND4")
		(24 "In11.Cu" signal "IN4")
		(26 "In12.Cu" signal "GND5")
		(28 "In13.Cu" signal "IN5")
		(30 "In14.Cu" signal "GND6")
		(32 "In15.Cu" signal "IN6")
		(34 "In16.Cu" signal "GND7")
		(2 "B.Cu" signal "BOTTOM")
		(9 "F.Adhes" user "F.Adhesive")
		(11 "B.Adhes" user "B.Adhesive")
		(13 "F.Paste" user "Package Geometry/Pastemask Top")
		(15 "B.Paste" user "Package Geometry/Pastemask Bottom")
		(5 "F.SilkS" user "Ref Des/Silkscreen Top")
		(7 "B.SilkS" user "Ref Des/Silkscreen Bottom")
		(1 "F.Mask" user "Board Geometry/Soldermask Top")
		(3 "B.Mask" user "Board Geometry/Soldermask Bottom")
		(17 "Dwgs.User" user "User.Drawings")
		(19 "Cmts.User" user "User.Comments")
		(21 "Eco1.User" user "User.Eco1")
		(23 "Eco2.User" user "User.Eco2")
		(25 "Edge.Cuts" user "Board Geometry/Outline")
		(27 "Margin" user)
		(31 "F.CrtYd" user "Package Geometry/Place Bound Top")
		(29 "B.CrtYd" user "Package Geometry/Place Bound Bottom")
		(35 "F.Fab" user "Ref Des/Assembly Top")
		(33 "B.Fab" user "Ref Des/Assembly Bottom")
	)
	(footprint ""
		(layer "B.Cu")
		(at 372.937278 -138.424158 180)
		(property "Reference" "R8310"
			(at 0 0 0)
			(layer "B.SilkS")
			(hide yes)
			(effects
				(font
					(size 1.27 1.27)
				)
				(justify mirror)
			)
		)
		(property "Value" ""
			(at 0 0 0)
			(layer "B.Fab")
			(effects
				(font
					(size 1.27 1.27)
				)
				(justify mirror)
			)
		)
		(duplicate_pad_numbers_are_jumpers no)
		(fp_line
			(start 0.7874 0.4064)
			(end 0.7874 -0.4064)
			(stroke
				(width 0.1524)
				(type default)
			)
			(layer "B.SilkS")
		)
		(fp_line
			(start 0.7874 -0.4064)
			(end -0.7874 -0.4064)
			(stroke
				(width 0.1524)
				(type default)
			)
			(layer "B.SilkS")
		)
		(fp_line
			(start -0.7874 0.4064)
			(end 0.7874 0.4064)
			(stroke
				(width 0.1524)
				(type default)
			)
			(layer "B.SilkS")
		)
		(fp_line
			(start -0.7874 -0.4064)
			(end -0.7874 0.4064)
			(stroke
				(width 0.1524)
				(type default)
			)
			(layer "B.SilkS")
		)
		(fp_line
			(start 0.67945 0.3048)
			(end 0.67945 -0.305054)
			(stroke
				(width 0.1)
				(type default)
			)
			(layer "B.Fab")
		)
		(fp_line
			(start 0.67945 -0.305054)
			(end 0.12065 -0.305054)
			(stroke
				(width 0.1)
				(type default)
			)
			(layer "B.Fab")
		)
		(fp_line
			(start 0.12065 0.3048)
			(end 0.67945 0.3048)
			(stroke
				(width 0.1)
				(type default)
			)
			(layer "B.Fab")
		)
		(fp_line
			(start 0.12065 0.2794)
			(end 0.12065 0.3048)
			(stroke
				(width 0.1)
				(type default)
			)
			(layer "B.Fab")
		)
		(fp_line
			(start 0.12065 -0.2794)
			(end -0.12065 -0.2794)
			(stroke
				(width 0.1)
				(type default)
			)
			(layer "B.Fab")
		)
		(fp_line
			(start 0.12065 -0.305054)
			(end 0.12065 -0.2794)
			(stroke
				(width 0.1)
				(type default)
			)
			(layer "B.Fab")
		)
		(fp_line
			(start -0.120396 0.3048)
			(end -0.120396 0.2794)
			(stroke
				(width 0.1)
				(type default)
			)
			(layer "B.Fab")
		)
		(fp_line
			(start -0.120396 0.2794)
			(end 0.12065 0.2794)
			(stroke
				(width 0.1)
				(type default)
			)
			(layer "B.Fab")
		)
		(fp_line
			(start -0.12065 -0.2794)
			(end -0.12065 -0.3048)
			(stroke
				(width 0.1)
				(type default)
			)
			(layer "B.Fab")
		)
		(fp_line
			(start -0.12065 -0.3048)
			(end -0.67945 -0.3048)
			(stroke
				(width 0.1)
				(type default)
			)
			(layer "B.Fab")
		)
		(fp_line
			(start -0.67945 0.3048)
			(end -0.120396 0.3048)
			(stroke
				(width 0.1)
				(type default)
			)
			(layer "B.Fab")
		)
		(fp_line
			(start -0.67945 -0.3048)
			(end -0.67945 0.3048)
			(stroke
				(width 0.1)
				(type default)
			)
			(layer "B.Fab")
		)
		(pad "1" smd circle
			(at 0.40005 0)
			(size 0 0)
			(layers "B.Cu" "B.Mask" "B.Paste")
			(net "PVDDCR_CPU0_P0_PMALERT")
		)
		(pad "2" smd circle
			(at -0.40005 0)
			(size 0 0)
			(layers "B.Cu" "B.Mask" "B.Paste")
			(net "PVDDCR_CPU0_P0_PMALERT_R")
		)
	)
	(footprint ""
		(layer "B.Cu")
		(at 457.148184 -65.768982 90)
		(property "Reference" "PC1600"
			(at 0 0 90)
			(layer "B.SilkS")
			(hide yes)
			(effects
				(font
					(size 1.27 1.27)
				)
				(justify mirror)
			)
		)
		(property "Value" ""
			(at 0 0 90)
			(layer "B.Fab")
			(effects
				(font
					(size 1.27 1.27)
				)
				(justify mirror)
			)
		)
		(duplicate_pad_numbers_are_jumpers no)
		(fp_line
			(start 1.524 -0.762)
			(end -1.524 -0.762)
			(stroke
				(width 0.1524)
				(type default)
			)
			(layer "B.SilkS")
		)
		(fp_line
			(start -1.524 -0.762)
			(end -1.524 0.762)
			(stroke
				(width 0.1524)
				(type default)
			)
			(layer "B.SilkS")
		)
		(fp_line
			(start 1.524 0.762)
			(end 1.524 -0.762)
			(stroke
				(width 0.1524)
				(type default)
			)
			(layer "B.SilkS")
		)
		(fp_line
			(start -1.524 0.762)
			(end 1.524 0.762)
			(stroke
				(width 0.1524)
				(type default)
			)
			(layer "B.SilkS")
		)
		(fp_line
			(start 1.1049 -0.724916)
			(end 1.1049 0.724916)
			(stroke
				(width 0.1)
				(type default)
			)
			(layer "B.Fab")
		)
		(fp_line
			(start -1.1049 -0.724916)
			(end 1.1049 -0.724916)
			(stroke
				(width 0.1)
				(type default)
			)
			(layer "B.Fab")
		)
		(fp_line
			(start 1.1049 0.724916)
			(end -1.1049 0.724916)
			(stroke
				(width 0.1)
				(type default)
			)
			(layer "B.Fab")
		)
		(fp_line
			(start -1.1049 0.724916)
			(end -1.1049 -0.724916)
			(stroke
				(width 0.1)
				(type default)
			)
			(layer "B.Fab")
		)
		(pad "1" smd rect
			(at 0.889 0 90)
			(size 1.016 1.27)
			(layers "B.Cu" "B.Mask" "B.Paste")
			(net "P3V3_AUX")
		)
		(pad "2" smd rect
			(at -0.889 0 90)
			(size 1.016 1.27)
			(layers "B.Cu" "B.Mask" "B.Paste")
			(net "GND")
		)
	)
	(footprint ""
		(layer "B.Cu")
		(at 22.096984 -389.526526 -90)
		(property "Reference" "PR6627"
			(at 0 0 90)
			(layer "B.SilkS")
			(hide yes)
			(effects
				(font
					(size 1.27 1.27)
				)
				(justify mirror)
			)
		)
		(property "Value" ""
			(at 0 0 90)
			(layer "B.Fab")
			(effects
				(font
					(size 1.27 1.27)
				)
				(justify mirror)
			)
		)
		(duplicate_pad_numbers_are_jumpers no)
		(fp_line
			(start -0.7874 0.4064)
			(end 0.7874 0.4064)
			(stroke
				(width 0.1524)
				(type default)
			)
			(layer "B.SilkS")
		)
		(fp_line
			(start 0.7874 0.4064)
			(end 0.7874 -0.4064)
			(stroke
				(width 0.1524)
				(type default)
			)
			(layer "B.SilkS")
		)
		(fp_line
			(start -0.7874 -0.4064)
			(end -0.7874 0.4064)
			(stroke
				(width 0.1524)
				(type default)
			)
			(layer "B.SilkS")
		)
		(fp_line
			(start 0.7874 -0.4064)
			(end -0.7874 -0.4064)
			(stroke
				(width 0.1524)
				(type default)
			)
			(layer "B.SilkS")
		)
		(fp_line
			(start -0.67945 0.3048)
			(end -0.120396 0.3048)
			(stroke
				(width 0.1)
				(type default)
			)
			(layer "B.Fab")
		)
		(fp_line
			(start -0.120396 0.3048)
			(end -0.120396 0.2794)
			(stroke
				(width 0.1)
				(type default)
			)
			(layer "B.Fab")
		)
		(fp_line
			(start 0.12065 0.3048)
			(end 0.67945 0.3048)
			(stroke
				(width 0.1)
				(type default)
			)
			(layer "B.Fab")
		)
		(fp_line
			(start 0.67945 0.3048)
			(end 0.67945 -0.305054)
			(stroke
				(width 0.1)
				(type default)
			)
			(layer "B.Fab")
		)
		(fp_line
			(start -0.120396 0.2794)
			(end 0.12065 0.2794)
			(stroke
				(width 0.1)
				(type default)
			)
			(layer "B.Fab")
		)
		(fp_line
			(start 0.12065 0.2794)
			(end 0.12065 0.3048)
			(stroke
				(width 0.1)
				(type default)
			)
			(layer "B.Fab")
		)
		(fp_line
			(start -0.12065 -0.2794)
			(end -0.12065 -0.3048)
			(stroke
				(width 0.1)
				(type default)
			)
			(layer "B.Fab")
		)
		(fp_line
			(start 0.12065 -0.2794)
			(end -0.12065 -0.2794)
			(stroke
				(width 0.1)
				(type default)
			)
			(layer "B.Fab")
		)
		(fp_line
			(start -0.67945 -0.3048)
			(end -0.67945 0.3048)
			(stroke
				(width 0.1)
				(type default)
			)
			(layer "B.Fab")
		)
		(fp_line
			(start -0.12065 -0.3048)
			(end -0.67945 -0.3048)
			(stroke
				(width 0.1)
				(type default)
			)
			(layer "B.Fab")
		)
		(fp_line
			(start 0.12065 -0.305054)
			(end 0.12065 -0.2794)
			(stroke
				(width 0.1)
				(type default)
			)
			(layer "B.Fab")
		)
		(fp_line
			(start 0.67945 -0.305054)
			(end 0.12065 -0.305054)
			(stroke
				(width 0.1)
				(type default)
			)
			(layer "B.Fab")
		)
		(pad "1" smd circle
			(at 0.40005 0 90)
			(size 0 0)
			(layers "B.Cu" "B.Mask" "B.Paste")
			(net "P0V9_RETIMER_CPU1_PVCC")
		)
		(pad "2" smd circle
			(at -0.40005 0 90)
			(size 0 0)
			(layers "B.Cu" "B.Mask" "B.Paste")
			(net "P0V9_RETIMER_CPU1_VCC2")
		)
	)
)
